# S9S_MB_2U (Grand Teton) — schematic netlist excerpt (pin names and nets, part order shuffled) for the footprints in the layout excerpt that follows; sources: Cadence DE-HDL packaged netlist, KiCad conversion of 03242023_DA0F0TMBIJ0_F0T_Motherboard_J_brd_V01_OCP.brd

C761  Q_CAP_DIFFBUS  DIFF BUS_0.22UF 6.3V 20% X6S  pkg C0201  page 176 : \1\ = P5E_CPU1_PE2_TX_C_DP<6> ; \2\ = P5E_CPU1_PE2_TX_DP<6>
R4203  Q_RES  1K 1% CHIP  pkg 0402LF  page 170 : A = U272_2_ADD0 ; B = GND
C870  Q_CAP_DIFFBUS  DIFF BUS_0.22UF 6.3V 20% X6S  pkg C0201  page 174 : \1\ = P5E_CPU0_PE3_TX_C_DN<15> ; \2\ = P5E_CPU0_PE3_TX_DN<15>

(kicad_pcb
	(version 20260206)
	(generator "pcbnew")
	(generator_version "10.0")
	(general
		(thickness 1.6)
		(legacy_teardrops no)
	)
	(paper "A4")
	(title_block
		(title "03242023_DA0F0TMBIJ0_F0T_Motherboard_J_brd_V01_OCP.brd")
		(comment 1 "Grand Teton / footprints 1929-1931 of 6105")
	)
	(layers
		(0 "F.Cu" signal "TOP")
		(4 "In1.Cu" signal "GND")
		(6 "In2.Cu" signal "IN1")
		(8 "In3.Cu" signal "GND1")
		(10 "In4.Cu" signal "IN2")
		(12 "In5.Cu" signal "GND2")
		(14 "In6.Cu" signal "IN3")
		(16 "In7.Cu" signal "GND3")
		(18 "In8.Cu" signal "VCC")
		(20 "In9.Cu" signal "VCC1")
		(22 "In10.Cu" signal "GND4")
		(24 "In11.Cu" signal "IN4")
		(26 "In12.Cu" signal "GND5")
		(28 "In13.Cu" signal "IN5")
		(30 "In14.Cu" signal "GND6")
		(32 "In15.Cu" signal "IN6")
		(34 "In16.Cu" signal "GND7")
		(2 "B.Cu" signal "BOTTOM")
		(9 "F.Adhes" user "F.Adhesive")
		(11 "B.Adhes" user "B.Adhesive")
		(13 "F.Paste" user "Package Geometry/Pastemask Top")
		(15 "B.Paste" user "Package Geometry/Pastemask Bottom")
		(5 "F.SilkS" user "Ref Des/Silkscreen Top")
		(7 "B.SilkS" user "Ref Des/Silkscreen Bottom")
		(1 "F.Mask" user "Board Geometry/Soldermask Top")
		(3 "B.Mask" user "Board Geometry/Soldermask Bottom")
		(17 "Dwgs.User" user "User.Drawings")
		(19 "Cmts.User" user "User.Comments")
		(21 "Eco1.User" user "User.Eco1")
		(23 "Eco2.User" user "User.Eco2")
		(25 "Edge.Cuts" user "Board Geometry/Outline")
		(27 "Margin" user)
		(31 "F.CrtYd" user "Package Geometry/Place Bound Top")
		(29 "B.CrtYd" user "Package Geometry/Place Bound Bottom")
		(35 "F.Fab" user "Ref Des/Assembly Top")
		(33 "B.Fab" user "Ref Des/Assembly Bottom")
	)
	(footprint ""
		(layer "F.Cu")
		(at 147.698714 -402.371052 -90)
		(property "Reference" "C761"
			(at 0 0 270)
			(layer "F.SilkS")
			(hide yes)
			(effects
				(font
					(size 1.27 1.27)
				)
			)
		)
		(property "Value" ""
			(at 0 0 270)
			(layer "F.Fab")
			(effects
				(font
					(size 1.27 1.27)
				)
			)
		)
		(duplicate_pad_numbers_are_jumpers no)
		(fp_line
			(start -0.299974 0.150114)
			(end -0.299974 -0.150114)
			(stroke
				(width 0.1)
				(type default)
			)
			(layer "F.Fab")
		)
		(fp_line
			(start 0.299974 0.150114)
			(end -0.299974 0.150114)
			(stroke
				(width 0.1)
				(type default)
			)
			(layer "F.Fab")
		)
		(fp_line
			(start -0.299974 -0.150114)
			(end 0.299974 -0.150114)
			(stroke
				(width 0.1)
				(type default)
			)
			(layer "F.Fab")
		)
		(fp_line
			(start 0.299974 -0.150114)
			(end 0.299974 0.150114)
			(stroke
				(width 0.1)
				(type default)
			)
			(layer "F.Fab")
		)
		(pad "1" smd rect
			(at -0.2667 0 270)
			(size 0.3048 0.381)
			(layers "F.Cu" "F.Mask" "F.Paste")
			(net "P5E_CPU1_PE2_TX_C_DP<6>")
		)
		(pad "2" smd rect
			(at 0.2667 0 270)
			(size 0.3048 0.381)
			(layers "F.Cu" "F.Mask" "F.Paste")
			(net "P5E_CPU1_PE2_TX_DP<6>")
		)
	)
	(footprint ""
		(layer "F.Cu")
		(at 99.388422 -414.776666 -90)
		(property "Reference" "R4203"
			(at 0 0 270)
			(layer "F.SilkS")
			(hide yes)
			(effects
				(font
					(size 1.27 1.27)
				)
			)
		)
		(property "Value" ""
			(at 0 0 270)
			(layer "F.Fab")
			(effects
				(font
					(size 1.27 1.27)
				)
			)
		)
		(duplicate_pad_numbers_are_jumpers no)
		(fp_line
			(start -0.7874 0.4064)
			(end -0.7874 -0.4064)
			(stroke
				(width 0.1524)
				(type default)
			)
			(layer "F.SilkS")
		)
		(fp_line
			(start 0.7874 0.4064)
			(end -0.7874 0.4064)
			(stroke
				(width 0.1524)
				(type default)
			)
			(layer "F.SilkS")
		)
		(fp_line
			(start -0.7874 -0.4064)
			(end 0.7874 -0.4064)
			(stroke
				(width 0.1524)
				(type default)
			)
			(layer "F.SilkS")
		)
		(fp_line
			(start 0.7874 -0.4064)
			(end 0.7874 0.4064)
			(stroke
				(width 0.1524)
				(type default)
			)
			(layer "F.SilkS")
		)
		(fp_line
			(start -0.67945 0.3048)
			(end -0.67945 -0.305054)
			(stroke
				(width 0.1)
				(type default)
			)
			(layer "F.Fab")
		)
		(fp_line
			(start -0.12065 0.3048)
			(end -0.67945 0.3048)
			(stroke
				(width 0.1)
				(type default)
			)
			(layer "F.Fab")
		)
		(fp_line
			(start 0.120396 0.3048)
			(end 0.120396 0.2794)
			(stroke
				(width 0.1)
				(type default)
			)
			(layer "F.Fab")
		)
		(fp_line
			(start 0.67945 0.3048)
			(end 0.120396 0.3048)
			(stroke
				(width 0.1)
				(type default)
			)
			(layer "F.Fab")
		)
		(fp_line
			(start -0.12065 0.2794)
			(end -0.12065 0.3048)
			(stroke
				(width 0.1)
				(type default)
			)
			(layer "F.Fab")
		)
		(fp_line
			(start 0.120396 0.2794)
			(end -0.12065 0.2794)
			(stroke
				(width 0.1)
				(type default)
			)
			(layer "F.Fab")
		)
		(fp_line
			(start -0.12065 -0.2794)
			(end 0.12065 -0.2794)
			(stroke
				(width 0.1)
				(type default)
			)
			(layer "F.Fab")
		)
		(fp_line
			(start 0.12065 -0.2794)
			(end 0.12065 -0.3048)
			(stroke
				(width 0.1)
				(type default)
			)
			(layer "F.Fab")
		)
		(fp_line
			(start 0.12065 -0.3048)
			(end 0.67945 -0.3048)
			(stroke
				(width 0.1)
				(type default)
			)
			(layer "F.Fab")
		)
		(fp_line
			(start 0.67945 -0.3048)
			(end 0.67945 0.3048)
			(stroke
				(width 0.1)
				(type default)
			)
			(layer "F.Fab")
		)
		(fp_line
			(start -0.67945 -0.305054)
			(end -0.12065 -0.305054)
			(stroke
				(width 0.1)
				(type default)
			)
			(layer "F.Fab")
		)
		(fp_line
			(start -0.12065 -0.305054)
			(end -0.12065 -0.2794)
			(stroke
				(width 0.1)
				(type default)
			)
			(layer "F.Fab")
		)
		(pad "1" smd circle
			(at -0.40005 0 270)
			(size 0 0)
			(layers "F.Cu" "F.Mask" "F.Paste")
			(net "U272_2_ADD0")
		)
		(pad "2" smd circle
			(at 0.40005 0 270)
			(size 0 0)
			(layers "F.Cu" "F.Mask" "F.Paste")
			(net "GND")
		)
	)
	(footprint ""
		(layer "F.Cu")
		(at 372.74373 -408.517344 -90)
		(property "Reference" "C870"
			(at 0 0 270)
			(layer "F.SilkS")
			(hide yes)
			(effects
				(font
					(size 1.27 1.27)
				)
			)
		)
		(property "Value" ""
			(at 0 0 270)
			(layer "F.Fab")
			(effects
				(font
					(size 1.27 1.27)
				)
			)
		)
		(duplicate_pad_numbers_are_jumpers no)
		(fp_line
			(start -0.299974 0.150114)
			(end -0.299974 -0.150114)
			(stroke
				(width 0.1)
				(type default)
			)
			(layer "F.Fab")
		)
		(fp_line
			(start 0.299974 0.150114)
			(end -0.299974 0.150114)
			(stroke
				(width 0.1)
				(type default)
			)
			(layer "F.Fab")
		)
		(fp_line
			(start -0.299974 -0.150114)
			(end 0.299974 -0.150114)
			(stroke
				(width 0.1)
				(type default)
			)
			(layer "F.Fab")
		)
		(fp_line
			(start 0.299974 -0.150114)
			(end 0.299974 0.150114)
			(stroke
				(width 0.1)
				(type default)
			)
			(layer "F.Fab")
		)
		(pad "1" smd rect
			(at -0.2667 0 270)
			(size 0.3048 0.381)
			(layers "F.Cu" "F.Mask" "F.Paste")
			(net "P5E_CPU0_PE3_TX_C_DN<15>")
		)
		(pad "2" smd rect
			(at 0.2667 0 270)
			(size 0.3048 0.381)
			(layers "F.Cu" "F.Mask" "F.Paste")
			(net "P5E_CPU0_PE3_TX_DN<15>")
		)
	)
)
